(kicad_pcb
	(version 20260206)
	(generator "pcbnew")
	(generator_version "10.0")
	(general
		(thickness 1.6)
		(legacy_teardrops no)
	)
	(paper "A4")
	(title_block
		(title "03242023_DA0F0TMBIJ0_F0T_Motherboard_J_brd_V01_OCP.brd")
		(comment 1 "Grand Teton / footprints 5904-5911 of 6105")
	)
	(layers
		(0 "F.Cu" signal "TOP")
		(4 "In1.Cu" signal "GND")
		(6 "In2.Cu" signal "IN1")
		(8 "In3.Cu" signal "GND1")
		(10 "In4.Cu" signal "IN2")
		(12 "In5.Cu" signal "GND2")
		(14 "In6.Cu" signal "IN3")
		(16 "In7.Cu" signal "GND3")
		(18 "In8.Cu" signal "VCC")
		(20 "In9.Cu" signal "VCC1")
		(22 "In10.Cu" signal "GND4")
		(24 "In11.Cu" signal "IN4")
		(26 "In12.Cu" signal "GND5")
		(28 "In13.Cu" signal "IN5")
		(30 "In14.Cu" signal "GND6")
		(32 "In15.Cu" signal "IN6")
		(34 "In16.Cu" signal "GND7")
		(2 "B.Cu" signal "BOTTOM")
		(9 "F.Adhes" user "F.Adhesive")
		(11 "B.Adhes" user "B.Adhesive")
		(13 "F.Paste" user "Package Geometry/Pastemask Top")
		(15 "B.Paste" user "Package Geometry/Pastemask Bottom")
		(5 "F.SilkS" user "Ref Des/Silkscreen Top")
		(7 "B.SilkS" user "Ref Des/Silkscreen Bottom")
		(1 "F.Mask" user "Board Geometry/Soldermask Top")
		(3 "B.Mask" user "Board Geometry/Soldermask Bottom")
		(17 "Dwgs.User" user "User.Drawings")
		(19 "Cmts.User" user "User.Comments")
		(21 "Eco1.User" user "User.Eco1")
		(23 "Eco2.User" user "User.Eco2")
		(25 "Edge.Cuts" user "Board Geometry/Outline")
		(27 "Margin" user)
		(31 "F.CrtYd" user "Package Geometry/Place Bound Top")
		(29 "B.CrtYd" user "Package Geometry/Place Bound Bottom")
		(35 "F.Fab" user "Ref Des/Assembly Top")
		(33 "B.Fab" user "Ref Des/Assembly Bottom")
	)
	(footprint ""
		(layer "B.Cu")
		(at 13.649452 -101.21138 90)
		(property "Reference" "C2035"
			(at 0 0 90)
			(layer "B.SilkS")
			(hide yes)
			(effects
				(font
					(size 1.27 1.27)
				)
				(justify mirror)
			)
		)
		(property "Value" ""
			(at 0 0 90)
			(layer "B.Fab")
			(effects
				(font
					(size 1.27 1.27)
				)
				(justify mirror)
			)
		)
		(duplicate_pad_numbers_are_jumpers no)
		(fp_line
			(start 0.7874 -0.4064)
			(end -0.7874 -0.4064)
			(stroke
				(width 0.1524)
				(type default)
			)
			(layer "B.SilkS")
		)
		(fp_line
			(start -0.7874 -0.4064)
			(end -0.7874 0.4064)
			(stroke
				(width 0.1524)
				(type default)
			)
			(layer "B.SilkS")
		)
		(fp_line
			(start 0.7874 0.4064)
			(end 0.7874 -0.4064)
			(stroke
				(width 0.1524)
				(type default)
			)
			(layer "B.SilkS")
		)
		(fp_line
			(start -0.7874 0.4064)
			(end 0.7874 0.4064)
			(stroke
				(width 0.1524)
				(type default)
			)
			(layer "B.SilkS")
		)
		(fp_line
			(start 0.67945 -0.305054)
			(end 0.12065 -0.305054)
			(stroke
				(width 0.1)
				(type default)
			)
			(layer "B.Fab")
		)
		(fp_line
			(start 0.12065 -0.305054)
			(end 0.12065 -0.2794)
			(stroke
				(width 0.1)
				(type default)
			)
			(layer "B.Fab")
		)
		(fp_line
			(start -0.12065 -0.3048)
			(end -0.67945 -0.3048)
			(stroke
				(width 0.1)
				(type default)
			)
			(layer "B.Fab")
		)
		(fp_line
			(start -0.67945 -0.3048)
			(end -0.67945 0.3048)
			(stroke
				(width 0.1)
				(type default)
			)
			(layer "B.Fab")
		)
		(fp_line
			(start 0.12065 -0.2794)
			(end -0.12065 -0.2794)
			(stroke
				(width 0.1)
				(type default)
			)
			(layer "B.Fab")
		)
		(fp_line
			(start -0.12065 -0.2794)
			(end -0.12065 -0.3048)
			(stroke
				(width 0.1)
				(type default)
			)
			(layer "B.Fab")
		)
		(fp_line
			(start 0.12065 0.2794)
			(end 0.12065 0.3048)
			(stroke
				(width 0.1)
				(type default)
			)
			(layer "B.Fab")
		)
		(fp_line
			(start -0.120396 0.2794)
			(end 0.12065 0.2794)
			(stroke
				(width 0.1)
				(type default)
			)
			(layer "B.Fab")
		)
		(fp_line
			(start 0.67945 0.3048)
			(end 0.67945 -0.305054)
			(stroke
				(width 0.1)
				(type default)
			)
			(layer "B.Fab")
		)
		(fp_line
			(start 0.12065 0.3048)
			(end 0.67945 0.3048)
			(stroke
				(width 0.1)
				(type default)
			)
			(layer "B.Fab")
		)
		(fp_line
			(start -0.120396 0.3048)
			(end -0.120396 0.2794)
			(stroke
				(width 0.1)
				(type default)
			)
			(layer "B.Fab")
		)
		(fp_line
			(start -0.67945 0.3048)
			(end -0.120396 0.3048)
			(stroke
				(width 0.1)
				(type default)
			)
			(layer "B.Fab")
		)
		(pad "1" smd circle
			(at 0.40005 0 270)
			(size 0 0)
			(layers "B.Cu" "B.Mask" "B.Paste")
			(net "P3V3_AUX_USB_HUB")
		)
		(pad "2" smd circle
			(at -0.40005 0 270)
			(size 0 0)
			(layers "B.Cu" "B.Mask" "B.Paste")
			(net "GND")
		)
	)
	(footprint ""
		(layer "B.Cu")
		(at 416.02914 -158.92907)
		(property "Reference" "PC637"
			(at 0 0 0)
			(layer "B.SilkS")
			(hide yes)
			(effects
				(font
					(size 1.27 1.27)
				)
				(justify mirror)
			)
		)
		(property "Value" ""
			(at 0 0 0)
			(layer "B.Fab")
			(effects
				(font
					(size 1.27 1.27)
				)
				(justify mirror)
			)
		)
		(duplicate_pad_numbers_are_jumpers no)
		(fp_line
			(start -1.524 -0.762)
			(end -1.524 0.762)
			(stroke
				(width 0.1524)
				(type default)
			)
			(layer "B.SilkS")
		)
		(fp_line
			(start -1.524 0.762)
			(end 1.524 0.762)
			(stroke
				(width 0.1524)
				(type default)
			)
			(layer "B.SilkS")
		)
		(fp_line
			(start 1.524 -0.762)
			(end -1.524 -0.762)
			(stroke
				(width 0.1524)
				(type default)
			)
			(layer "B.SilkS")
		)
		(fp_line
			(start 1.524 0.762)
			(end 1.524 -0.762)
			(stroke
				(width 0.1524)
				(type default)
			)
			(layer "B.SilkS")
		)
		(fp_line
			(start -1.1049 -0.724916)
			(end 1.1049 -0.724916)
			(stroke
				(width 0.1)
				(type default)
			)
			(layer "B.Fab")
		)
		(fp_line
			(start -1.1049 0.724916)
			(end -1.1049 -0.724916)
			(stroke
				(width 0.1)
				(type default)
			)
			(layer "B.Fab")
		)
		(fp_line
			(start 1.1049 -0.724916)
			(end 1.1049 0.724916)
			(stroke
				(width 0.1)
				(type default)
			)
			(layer "B.Fab")
		)
		(fp_line
			(start 1.1049 0.724916)
			(end -1.1049 0.724916)
			(stroke
				(width 0.1)
				(type default)
			)
			(layer "B.Fab")
		)
		(pad "1" smd rect
			(at 0.889 0)
			(size 1.016 1.27)
			(layers "B.Cu" "B.Mask" "B.Paste")
			(net "SW_P12V_PVCCINFAON_CPU0_FLT")
		)
		(pad "2" smd rect
			(at -0.889 0)
			(size 1.016 1.27)
			(layers "B.Cu" "B.Mask" "B.Paste")
			(net "GND")
		)
	)
	(footprint ""
		(layer "B.Cu")
		(at 180.364384 -422.615868)
		(property "Reference" "R2805"
			(at 0 0 0)
			(layer "B.SilkS")
			(hide yes)
			(effects
				(font
					(size 1.27 1.27)
				)
				(justify mirror)
			)
		)
		(property "Value" ""
			(at 0 0 0)
			(layer "B.Fab")
			(effects
				(font
					(size 1.27 1.27)
				)
				(justify mirror)
			)
		)
		(duplicate_pad_numbers_are_jumpers no)
		(fp_line
			(start -0.7874 -0.4064)
			(end -0.7874 0.4064)
			(stroke
				(width 0.1524)
				(type default)
			)
			(layer "B.SilkS")
		)
		(fp_line
			(start -0.7874 0.4064)
			(end 0.7874 0.4064)
			(stroke
				(width 0.1524)
				(type default)
			)
			(layer "B.SilkS")
		)
		(fp_line
			(start 0.7874 -0.4064)
			(end -0.7874 -0.4064)
			(stroke
				(width 0.1524)
				(type default)
			)
			(layer "B.SilkS")
		)
		(fp_line
			(start 0.7874 0.4064)
			(end 0.7874 -0.4064)
			(stroke
				(width 0.1524)
				(type default)
			)
			(layer "B.SilkS")
		)
		(fp_line
			(start -0.67945 -0.3048)
			(end -0.67945 0.3048)
			(stroke
				(width 0.1)
				(type default)
			)
			(layer "B.Fab")
		)
		(fp_line
			(start -0.67945 0.3048)
			(end -0.120396 0.3048)
			(stroke
				(width 0.1)
				(type default)
			)
			(layer "B.Fab")
		)
		(fp_line
			(start -0.12065 -0.3048)
			(end -0.67945 -0.3048)
			(stroke
				(width 0.1)
				(type default)
			)
			(layer "B.Fab")
		)
		(fp_line
			(start -0.12065 -0.2794)
			(end -0.12065 -0.3048)
			(stroke
				(width 0.1)
				(type default)
			)
			(layer "B.Fab")
		)
		(fp_line
			(start -0.120396 0.2794)
			(end 0.12065 0.2794)
			(stroke
				(width 0.1)
				(type default)
			)
			(layer "B.Fab")
		)
		(fp_line
			(start -0.120396 0.3048)
			(end -0.120396 0.2794)
			(stroke
				(width 0.1)
				(type default)
			)
			(layer "B.Fab")
		)
		(fp_line
			(start 0.12065 -0.305054)
			(end 0.12065 -0.2794)
			(stroke
				(width 0.1)
				(type default)
			)
			(layer "B.Fab")
		)
		(fp_line
			(start 0.12065 -0.2794)
			(end -0.12065 -0.2794)
			(stroke
				(width 0.1)
				(type default)
			)
			(layer "B.Fab")
		)
		(fp_line
			(start 0.12065 0.2794)
			(end 0.12065 0.3048)
			(stroke
				(width 0.1)
				(type default)
			)
			(layer "B.Fab")
		)
		(fp_line
			(start 0.12065 0.3048)
			(end 0.67945 0.3048)
			(stroke
				(width 0.1)
				(type default)
			)
			(layer "B.Fab")
		)
		(fp_line
			(start 0.67945 -0.305054)
			(end 0.12065 -0.305054)
			(stroke
				(width 0.1)
				(type default)
			)
			(layer "B.Fab")
		)
		(fp_line
			(start 0.67945 0.3048)
			(end 0.67945 -0.305054)
			(stroke
				(width 0.1)
				(type default)
			)
			(layer "B.Fab")
		)
		(pad "1" smd circle
			(at 0.40005 0 180)
			(size 0 0)
			(layers "B.Cu" "B.Mask" "B.Paste")
			(net "P3V3_AUX")
		)
		(pad "2" smd circle
			(at -0.40005 0 180)
			(size 0 0)
			(layers "B.Cu" "B.Mask" "B.Paste")
			(net "SMB_FAN_3V3AUX_BUF_SCL")
		)
	)
	(footprint ""
		(layer "B.Cu")
		(at 330.17206 -32.700468 -90)
		(property "Reference" "R374"
			(at 0 0 90)
			(layer "B.SilkS")
			(hide yes)
			(effects
				(font
					(size 1.27 1.27)
				)
				(justify mirror)
			)
		)
		(property "Value" ""
			(at 0 0 90)
			(layer "B.Fab")
			(effects
				(font
					(size 1.27 1.27)
				)
				(justify mirror)
			)
		)
		(duplicate_pad_numbers_are_jumpers no)
		(fp_line
			(start -0.7874 0.4064)
			(end 0.7874 0.4064)
			(stroke
				(width 0.1524)
				(type default)
			)
			(layer "B.SilkS")
		)
		(fp_line
			(start 0.7874 0.4064)
			(end 0.7874 -0.4064)
			(stroke
				(width 0.1524)
				(type default)
			)
			(layer "B.SilkS")
		)
		(fp_line
			(start -0.7874 -0.4064)
			(end -0.7874 0.4064)
			(stroke
				(width 0.1524)
				(type default)
			)
			(layer "B.SilkS")
		)
		(fp_line
			(start 0.7874 -0.4064)
			(end -0.7874 -0.4064)
			(stroke
				(width 0.1524)
				(type default)
			)
			(layer "B.SilkS")
		)
		(fp_line
			(start -0.67945 0.3048)
			(end -0.120396 0.3048)
			(stroke
				(width 0.1)
				(type default)
			)
			(layer "B.Fab")
		)
		(fp_line
			(start -0.120396 0.3048)
			(end -0.120396 0.2794)
			(stroke
				(width 0.1)
				(type default)
			)
			(layer "B.Fab")
		)
		(fp_line
			(start 0.12065 0.3048)
			(end 0.67945 0.3048)
			(stroke
				(width 0.1)
				(type default)
			)
			(layer "B.Fab")
		)
		(fp_line
			(start 0.67945 0.3048)
			(end 0.67945 -0.305054)
			(stroke
				(width 0.1)
				(type default)
			)
			(layer "B.Fab")
		)
		(fp_line
			(start -0.120396 0.2794)
			(end 0.12065 0.2794)
			(stroke
				(width 0.1)
				(type default)
			)
			(layer "B.Fab")
		)
		(fp_line
			(start 0.12065 0.2794)
			(end 0.12065 0.3048)
			(stroke
				(width 0.1)
				(type default)
			)
			(layer "B.Fab")
		)
		(fp_line
			(start -0.12065 -0.2794)
			(end -0.12065 -0.3048)
			(stroke
				(width 0.1)
				(type default)
			)
			(layer "B.Fab")
		)
		(fp_line
			(start 0.12065 -0.2794)
			(end -0.12065 -0.2794)
			(stroke
				(width 0.1)
				(type default)
			)
			(layer "B.Fab")
		)
		(fp_line
			(start -0.67945 -0.3048)
			(end -0.67945 0.3048)
			(stroke
				(width 0.1)
				(type default)
			)
			(layer "B.Fab")
		)
		(fp_line
			(start -0.12065 -0.3048)
			(end -0.67945 -0.3048)
			(stroke
				(width 0.1)
				(type default)
			)
			(layer "B.Fab")
		)
		(fp_line
			(start 0.12065 -0.305054)
			(end 0.12065 -0.2794)
			(stroke
				(width 0.1)
				(type default)
			)
			(layer "B.Fab")
		)
		(fp_line
			(start 0.67945 -0.305054)
			(end 0.12065 -0.305054)
			(stroke
				(width 0.1)
				(type default)
			)
			(layer "B.Fab")
		)
		(pad "1" smd circle
			(at 0.40005 0 90)
			(size 0 0)
			(layers "B.Cu" "B.Mask" "B.Paste")
			(net "P3V3_AUX")
		)
		(pad "2" smd circle
			(at -0.40005 0 90)
			(size 0 0)
			(layers "B.Cu" "B.Mask" "B.Paste")
			(net "FM_SPI_3V3_1V8_VOLTAGE")
		)
	)
	(footprint ""
		(layer "B.Cu")
		(at 21.97608 -389.829548 -90)
		(property "Reference" "C1867"
			(at 0 0 90)
			(layer "B.SilkS")
			(hide yes)
			(effects
				(font
					(size 1.27 1.27)
				)
				(justify mirror)
			)
		)
		(property "Value" ""
			(at 0 0 90)
			(layer "B.Fab")
			(effects
				(font
					(size 1.27 1.27)
				)
				(justify mirror)
			)
		)
		(duplicate_pad_numbers_are_jumpers no)
		(fp_line
			(start -1.524 0.762)
			(end 1.524 0.762)
			(stroke
				(width 0.1524)
				(type default)
			)
			(layer "B.SilkS")
		)
		(fp_line
			(start 1.524 0.762)
			(end 1.524 -0.762)
			(stroke
				(width 0.1524)
				(type default)
			)
			(layer "B.SilkS")
		)
		(fp_line
			(start -1.524 -0.762)
			(end -1.524 0.762)
			(stroke
				(width 0.1524)
				(type default)
			)
			(layer "B.SilkS")
		)
		(fp_line
			(start 1.524 -0.762)
			(end -1.524 -0.762)
			(stroke
				(width 0.1524)
				(type default)
			)
			(layer "B.SilkS")
		)
		(fp_line
			(start -1.1049 0.724916)
			(end -1.1049 -0.724916)
			(stroke
				(width 0.1)
				(type default)
			)
			(layer "B.Fab")
		)
		(fp_line
			(start 1.1049 0.724916)
			(end -1.1049 0.724916)
			(stroke
				(width 0.1)
				(type default)
			)
			(layer "B.Fab")
		)
		(fp_line
			(start -1.1049 -0.724916)
			(end 1.1049 -0.724916)
			(stroke
				(width 0.1)
				(type default)
			)
			(layer "B.Fab")
		)
		(fp_line
			(start 1.1049 -0.724916)
			(end 1.1049 0.724916)
			(stroke
				(width 0.1)
				(type default)
			)
			(layer "B.Fab")
		)
		(pad "1" smd rect
			(at 0.889 0 270)
			(size 1.016 1.27)
			(layers "B.Cu" "B.Mask" "B.Paste")
			(net "P3V3_AUX")
		)
		(pad "2" smd rect
			(at -0.889 0 270)
			(size 1.016 1.27)
			(layers "B.Cu" "B.Mask" "B.Paste")
			(net "GND")
		)
	)
	(footprint ""
		(layer "B.Cu")
		(at 312.963814 -321.549776 -90)
		(property "Reference" "C6"
			(at 0 0 90)
			(layer "B.SilkS")
			(hide yes)
			(effects
				(font
					(size 1.27 1.27)
				)
				(justify mirror)
			)
		)
		(property "Value" ""
			(at 0 0 90)
			(layer "B.Fab")
			(effects
				(font
					(size 1.27 1.27)
				)
				(justify mirror)
			)
		)
		(duplicate_pad_numbers_are_jumpers no)
		(fp_line
			(start -1.524 0.762)
			(end 1.524 0.762)
			(stroke
				(width 0.1524)
				(type default)
			)
			(layer "B.SilkS")
		)
		(fp_line
			(start 1.524 0.762)
			(end 1.524 -0.762)
			(stroke
				(width 0.1524)
				(type default)
			)
			(layer "B.SilkS")
		)
		(fp_line
			(start -1.524 -0.762)
			(end -1.524 0.762)
			(stroke
				(width 0.1524)
				(type default)
			)
			(layer "B.SilkS")
		)
		(fp_line
			(start 1.524 -0.762)
			(end -1.524 -0.762)
			(stroke
				(width 0.1524)
				(type default)
			)
			(layer "B.SilkS")
		)
		(fp_line
			(start -1.1049 0.724916)
			(end -1.1049 -0.724916)
			(stroke
				(width 0.1)
				(type default)
			)
			(layer "B.Fab")
		)
		(fp_line
			(start 1.1049 0.724916)
			(end -1.1049 0.724916)
			(stroke
				(width 0.1)
				(type default)
			)
			(layer "B.Fab")
		)
		(fp_line
			(start -1.1049 -0.724916)
			(end 1.1049 -0.724916)
			(stroke
				(width 0.1)
				(type default)
			)
			(layer "B.Fab")
		)
		(fp_line
			(start 1.1049 -0.724916)
			(end 1.1049 0.724916)
			(stroke
				(width 0.1)
				(type default)
			)
			(layer "B.Fab")
		)
		(pad "1" smd rect
			(at 0.889 0 270)
			(size 1.016 1.27)
			(layers "B.Cu" "B.Mask" "B.Paste")
			(net "P12V_S3_AUX_CPU0_NVDIMM")
		)
		(pad "2" smd rect
			(at -0.889 0 270)
			(size 1.016 1.27)
			(layers "B.Cu" "B.Mask" "B.Paste")
			(net "GND")
		)
	)
	(footprint ""
		(layer "B.Cu")
		(at 98.5012 -337.607402 -90)
		(property "Reference" "PC569_P1_1"
			(at 0 0 90)
			(layer "B.SilkS")
			(hide yes)
			(effects
				(font
					(size 1.27 1.27)
				)
				(justify mirror)
			)
		)
		(property "Value" ""
			(at 0 0 90)
			(layer "B.Fab")
			(effects
				(font
					(size 1.27 1.27)
				)
				(justify mirror)
			)
		)
		(duplicate_pad_numbers_are_jumpers no)
		(fp_line
			(start -1.524 0.762)
			(end 1.524 0.762)
			(stroke
				(width 0.1524)
				(type default)
			)
			(layer "B.SilkS")
		)
		(fp_line
			(start 1.524 0.762)
			(end 1.524 -0.762)
			(stroke
				(width 0.1524)
				(type default)
			)
			(layer "B.SilkS")
		)
		(fp_line
			(start -1.524 -0.762)
			(end -1.524 0.762)
			(stroke
				(width 0.1524)
				(type default)
			)
			(layer "B.SilkS")
		)
		(fp_line
			(start 1.524 -0.762)
			(end -1.524 -0.762)
			(stroke
				(width 0.1524)
				(type default)
			)
			(layer "B.SilkS")
		)
		(fp_line
			(start -1.1049 0.724916)
			(end -1.1049 -0.724916)
			(stroke
				(width 0.1)
				(type default)
			)
			(layer "B.Fab")
		)
		(fp_line
			(start 1.1049 0.724916)
			(end -1.1049 0.724916)
			(stroke
				(width 0.1)
				(type default)
			)
			(layer "B.Fab")
		)
		(fp_line
			(start -1.1049 -0.724916)
			(end 1.1049 -0.724916)
			(stroke
				(width 0.1)
				(type default)
			)
			(layer "B.Fab")
		)
		(fp_line
			(start 1.1049 -0.724916)
			(end 1.1049 0.724916)
			(stroke
				(width 0.1)
				(type default)
			)
			(layer "B.Fab")
		)
		(pad "1" smd rect
			(at 0.889 0 270)
			(size 1.016 1.27)
			(layers "B.Cu" "B.Mask" "B.Paste")
			(net "SW_P12V_PVCCIN_CPU1_FLT")
		)
		(pad "2" smd rect
			(at -0.889 0 270)
			(size 1.016 1.27)
			(layers "B.Cu" "B.Mask" "B.Paste")
			(net "GND")
		)
	)
	(footprint ""
		(layer "B.Cu")
		(at 133.5786 -26.8732 90)
		(property "Reference" "R4637"
			(at 0 0 90)
			(layer "B.SilkS")
			(hide yes)
			(effects
				(font
					(size 1.27 1.27)
				)
				(justify mirror)
			)
		)
		(property "Value" ""
			(at 0 0 90)
			(layer "B.Fab")
			(effects
				(font
					(size 1.27 1.27)
				)
				(justify mirror)
			)
		)
		(duplicate_pad_numbers_are_jumpers no)
		(fp_line
			(start 0.7874 -0.4064)
			(end -0.7874 -0.4064)
			(stroke
				(width 0.1524)
				(type default)
			)
			(layer "B.SilkS")
		)
		(fp_line
			(start -0.7874 -0.4064)
			(end -0.7874 0.4064)
			(stroke
				(width 0.1524)
				(type default)
			)
			(layer "B.SilkS")
		)
		(fp_line
			(start 0.7874 0.4064)
			(end 0.7874 -0.4064)
			(stroke
				(width 0.1524)
				(type default)
			)
			(layer "B.SilkS")
		)
		(fp_line
			(start -0.7874 0.4064)
			(end 0.7874 0.4064)
			(stroke
				(width 0.1524)
				(type default)
			)
			(layer "B.SilkS")
		)
		(fp_line
			(start 0.67945 -0.305054)
			(end 0.12065 -0.305054)
			(stroke
				(width 0.1)
				(type default)
			)
			(layer "B.Fab")
		)
		(fp_line
			(start 0.12065 -0.305054)
			(end 0.12065 -0.2794)
			(stroke
				(width 0.1)
				(type default)
			)
			(layer "B.Fab")
		)
		(fp_line
			(start -0.12065 -0.3048)
			(end -0.67945 -0.3048)
			(stroke
				(width 0.1)
				(type default)
			)
			(layer "B.Fab")
		)
		(fp_line
			(start -0.67945 -0.3048)
			(end -0.67945 0.3048)
			(stroke
				(width 0.1)
				(type default)
			)
			(layer "B.Fab")
		)
		(fp_line
			(start 0.12065 -0.2794)
			(end -0.12065 -0.2794)
			(stroke
				(width 0.1)
				(type default)
			)
			(layer "B.Fab")
		)
		(fp_line
			(start -0.12065 -0.2794)
			(end -0.12065 -0.3048)
			(stroke
				(width 0.1)
				(type default)
			)
			(layer "B.Fab")
		)
		(fp_line
			(start 0.12065 0.2794)
			(end 0.12065 0.3048)
			(stroke
				(width 0.1)
				(type default)
			)
			(layer "B.Fab")
		)
		(fp_line
			(start -0.120396 0.2794)
			(end 0.12065 0.2794)
			(stroke
				(width 0.1)
				(type default)
			)
			(layer "B.Fab")
		)
		(fp_line
			(start 0.67945 0.3048)
			(end 0.67945 -0.305054)
			(stroke
				(width 0.1)
				(type default)
			)
			(layer "B.Fab")
		)
		(fp_line
			(start 0.12065 0.3048)
			(end 0.67945 0.3048)
			(stroke
				(width 0.1)
				(type default)
			)
			(layer "B.Fab")
		)
		(fp_line
			(start -0.120396 0.3048)
			(end -0.120396 0.2794)
			(stroke
				(width 0.1)
				(type default)
			)
			(layer "B.Fab")
		)
		(fp_line
			(start -0.67945 0.3048)
			(end -0.120396 0.3048)
			(stroke
				(width 0.1)
				(type default)
			)
			(layer "B.Fab")
		)
		(pad "1" smd circle
			(at 0.40005 0 270)
			(size 0 0)
			(layers "B.Cu" "B.Mask" "B.Paste")
			(net "USB3_PCH_RX_DN<4>")
		)
		(pad "2" smd circle
			(at -0.40005 0 270)
			(size 0 0)
			(layers "B.Cu" "B.Mask" "B.Paste")
			(net "GND")
		)
	)
)
